#ISCELL
  pure_quanta quanta_title_block_c *
  *
#CELL
  pure_quanta genoa_sp5 *
  page52_i147
#CELL
  pure_quanta genoa_sp5 *
  page52_i148
#ISCELL
  standard offpage *
  page52_i149
#ISCELL
  standard offpage *
  page52_i150
#ISCELL
  mstr_standard tap *
  page52_i151
#ISCELL
  mstr_standard tap *
  page52_i152
#ISCELL
  standard tap *
  page52_i153
#ISCELL
  mstr_standard tap *
  page52_i154
#ISCELL
  mstr_standard tap *
  page52_i155
#ISCELL
  standard tap *
  page52_i156
#ISCELL
  standard tap *
  page52_i157
#ISCELL
  standard tap *
  page52_i158
#ISCELL
  standard tap *
  page52_i159
#ISCELL
  standard tap *
  page52_i160
#ISCELL
  standard tap *
  page52_i161
#ISCELL
  standard tap *
  page52_i162
#ISCELL
  standard tap *
  page52_i163
#ISCELL
  standard tap *
  page52_i164
#ISCELL
  standard tap *
  page52_i165
#ISCELL
  standard tap *
  page52_i166
#ISCELL
  standard tap *
  page52_i167
#ISCELL
  standard tap *
  page52_i168
#ISCELL
  standard tap *
  page52_i169
#ISCELL
  standard tap *
  page52_i170
#ISCELL
  standard tap *
  page52_i171
#ISCELL
  standard tap *
  page52_i172
#ISCELL
  standard tap *
  page52_i173
#ISCELL
  standard tap *
  page52_i174
#ISCELL
  standard tap *
  page52_i175
#ISCELL
  standard tap *
  page52_i176
#ISCELL
  standard tap *
  page52_i177
#ISCELL
  standard tap *
  page52_i178
#ISCELL
  standard tap *
  page52_i179
#ISCELL
  standard tap *
  page52_i180
#ISCELL
  standard tap *
  page52_i181
#ISCELL
  standard tap *
  page52_i182
#ISCELL
  standard offpage *
  page52_i183
#ISCELL
  standard offpage *
  page52_i184
#ISCELL
  mstr_standard tap *
  page52_i185
#ISCELL
  mstr_standard tap *
  page52_i186
#ISCELL
  standard tap *
  page52_i187
#ISCELL
  mstr_standard tap *
  page52_i188
#ISCELL
  mstr_standard tap *
  page52_i189
#ISCELL
  standard tap *
  page52_i190
#ISCELL
  standard tap *
  page52_i191
#ISCELL
  standard tap *
  page52_i192
#ISCELL
  standard tap *
  page52_i193
#ISCELL
  standard tap *
  page52_i194
#ISCELL
  standard tap *
  page52_i195
#ISCELL
  standard tap *
  page52_i196
#ISCELL
  standard tap *
  page52_i197
#ISCELL
  standard tap *
  page52_i198
#ISCELL
  standard tap *
  page52_i199
#ISCELL
  standard tap *
  page52_i200
#ISCELL
  standard tap *
  page52_i201
#ISCELL
  standard tap *
  page52_i202
#ISCELL
  standard tap *
  page52_i203
#ISCELL
  standard tap *
  page52_i204
#ISCELL
  standard tap *
  page52_i205
#ISCELL
  standard tap *
  page52_i206
#ISCELL
  standard tap *
  page52_i207
#ISCELL
  standard tap *
  page52_i208
#ISCELL
  standard tap *
  page52_i209
#ISCELL
  standard tap *
  page52_i210
#ISCELL
  standard tap *
  page52_i211
#ISCELL
  standard tap *
  page52_i212
#ISCELL
  standard tap *
  page52_i213
#ISCELL
  standard tap *
  page52_i214
#ISCELL
  standard tap *
  page52_i215
#ISCELL
  standard tap *
  page52_i216
#ISCELL
  mstr_standard tap *
  page52_i251
#ISCELL
  mstr_standard tap *
  page52_i253
#ISCELL
  mstr_standard tap *
  page52_i254
#ISCELL
  standard tap *
  page52_i255
#ISCELL
  standard tap *
  page52_i256
#ISCELL
  standard tap *
  page52_i257
#ISCELL
  standard tap *
  page52_i263
#ISCELL
  mstr_standard tap *
  page52_i285
#ISCELL
  standard tap *
  page52_i286
#ISCELL
  standard tap *
  page52_i287
#ISCELL
  standard tap *
  page52_i288
#ISCELL
  mstr_standard tap *
  page52_i292
#ISCELL
  mstr_standard tap *
  page52_i293
#ISCELL
  standard tap *
  page52_i294
#ISCELL
  standard tap *
  page52_i299
#ISCELL
  standard tap *
  page52_i302
#ISCELL
  mstr_standard tap *
  page52_i303
#ISCELL
  mstr_standard tap *
  page52_i304
#ISCELL
  standard tap *
  page52_i305
#ISCELL
  standard tap *
  page52_i306
#ISCELL
  standard tap *
  page52_i307
#ISCELL
  standard tap *
  page52_i308
#ISCELL
  standard tap *
  page52_i309
#ISCELL
  mstr_standard tap *
  page52_i310
#ISCELL
  standard tap *
  page52_i311
#ISCELL
  mstr_standard tap *
  page52_i312
#ISCELL
  standard tap *
  page52_i313
#ISCELL
  standard tap *
  page52_i314
#ISCELL
  standard tap *
  page52_i315
#ISCELL
  standard tap *
  page52_i316
#ISCELL
  standard tap *
  page52_i317
#ISCELL
  standard tap *
  page52_i318
#ISCELL
  standard offpage *
  page52_i319
#ISCELL
  standard offpage *
  page52_i320
#ISCELL
  mstr_standard tap *
  page52_i321
#ISCELL
  mstr_standard tap *
  page52_i322
#ISCELL
  mstr_standard tap *
  page52_i323
#ISCELL
  mstr_standard tap *
  page52_i324
#ISCELL
  mstr_standard tap *
  page52_i325
#ISCELL
  standard tap *
  page52_i326
#ISCELL
  standard tap *
  page52_i327
#ISCELL
  standard tap *
  page52_i328
#ISCELL
  standard tap *
  page52_i329
#ISCELL
  standard tap *
  page52_i330
#ISCELL
  standard tap *
  page52_i331
#ISCELL
  standard tap *
  page52_i332
#ISCELL
  standard tap *
  page52_i333
#ISCELL
  standard tap *
  page52_i334
#ISCELL
  standard tap *
  page52_i335
#ISCELL
  standard tap *
  page52_i336
#ISCELL
  standard tap *
  page52_i337
#ISCELL
  standard tap *
  page52_i338
#ISCELL
  standard tap *
  page52_i339
#ISCELL
  standard tap *
  page52_i340
#ISCELL
  standard tap *
  page52_i341
#ISCELL
  standard tap *
  page52_i342
#ISCELL
  standard tap *
  page52_i343
#ISCELL
  standard tap *
  page52_i344
#ISCELL
  standard tap *
  page52_i345
#ISCELL
  standard tap *
  page52_i346
#ISCELL
  standard tap *
  page52_i347
#ISCELL
  standard tap *
  page52_i348
#ISCELL
  standard tap *
  page52_i349
#ISCELL
  standard tap *
  page52_i350
#ISCELL
  standard tap *
  page52_i351
#ISCELL
  standard tap *
  page52_i352
#ISCELL
  standard offpage *
  page52_i353
#ISCELL
  standard offpage *
  page52_i354
